(kicad_pcb
	(version 20260206)
	(generator "pcbnew")
	(generator_version "10.0")
	(general
		(thickness 1.6)
		(legacy_teardrops no)
	)
	(paper "A4")
	(title_block
		(title "03242023_DA0F0TMBIJ0_F0T_Motherboard_J_brd_V01_OCP.brd")
		(comment 1 "Grand Teton / footprint 1585 of 6105 (U4), pads 562-673 of 749")
	)
	(layers
		(0 "F.Cu" signal "TOP")
		(4 "In1.Cu" signal "GND")
		(6 "In2.Cu" signal "IN1")
		(8 "In3.Cu" signal "GND1")
		(10 "In4.Cu" signal "IN2")
		(12 "In5.Cu" signal "GND2")
		(14 "In6.Cu" signal "IN3")
		(16 "In7.Cu" signal "GND3")
		(18 "In8.Cu" signal "VCC")
		(20 "In9.Cu" signal "VCC1")
		(22 "In10.Cu" signal "GND4")
		(24 "In11.Cu" signal "IN4")
		(26 "In12.Cu" signal "GND5")
		(28 "In13.Cu" signal "IN5")
		(30 "In14.Cu" signal "GND6")
		(32 "In15.Cu" signal "IN6")
		(34 "In16.Cu" signal "GND7")
		(2 "B.Cu" signal "BOTTOM")
		(9 "F.Adhes" user "F.Adhesive")
		(11 "B.Adhes" user "B.Adhesive")
		(13 "F.Paste" user "Package Geometry/Pastemask Top")
		(15 "B.Paste" user "Package Geometry/Pastemask Bottom")
		(5 "F.SilkS" user "Ref Des/Silkscreen Top")
		(7 "B.SilkS" user "Ref Des/Silkscreen Bottom")
		(1 "F.Mask" user "Board Geometry/Soldermask Top")
		(3 "B.Mask" user "Board Geometry/Soldermask Bottom")
		(17 "Dwgs.User" user "User.Drawings")
		(19 "Cmts.User" user "User.Comments")
		(21 "Eco1.User" user "User.Eco1")
		(23 "Eco2.User" user "User.Eco2")
		(25 "Edge.Cuts" user "Board Geometry/Outline")
		(27 "Margin" user)
		(31 "F.CrtYd" user "Package Geometry/Place Bound Top")
		(29 "B.CrtYd" user "Package Geometry/Place Bound Bottom")
		(35 "F.Fab" user "Ref Des/Assembly Top")
		(33 "B.Fab" user "Ref Des/Assembly Bottom")
	)
	(footprint ""
		(layer "F.Cu")
		(at 336.899758 -48.450246)
		(property "Reference" "U4"
			(at -13.479018 -11.486896 0)
			(unlocked yes)
			(layer "F.SilkS")
			(effects
				(font
					(size 0.7874 0.5842)
					(thickness 0.1524)
				)
				(justify left)
			)
		)
		(property "Value" ""
			(at 0 0 0)
			(layer "F.Fab")
			(effects
				(font
					(size 1.27 1.27)
				)
			)
		)
		(duplicate_pad_numbers_are_jumpers no)
		(pad "G32" smd circle
			(at 5.291582 -7.9883 180)
			(size 0.381 0.381)
			(layers "F.Cu" "F.Mask" "F.Paste")
			(net "DMI_CPU0_PCH_RX_DP<4>")
		)
		(pad "G36" smd circle
			(at 6.919722 -7.9883 180)
			(size 0.381 0.381)
			(layers "F.Cu" "F.Mask" "F.Paste")
			(net "DMI_CPU0_PCH_RX_DN<5>")
		)
		(pad "G40" smd circle
			(at 9.069832 -8.003794 180)
			(size 0.3048 0.3048)
			(layers "F.Cu" "F.Mask" "F.Paste")
			(net "TP_P3E_PCH_15_RX_DN")
		)
		(pad "G42" smd circle
			(at 9.899904 -8.003794 180)
			(size 0.3048 0.3048)
			(layers "F.Cu" "F.Mask" "F.Paste")
			(net "TP_P3E_PCH_15_RX_DP")
		)
		(pad "H1" smd oval
			(at -10.31494 -7.503668 270)
			(size 0.254 0.3302)
			(layers "F.Cu" "F.Mask" "F.Paste")
			(net "TP_PCH_RSVD<0>")
		)
		(pad "H3" smd circle
			(at -9.484868 -7.503668 180)
			(size 0.3048 0.3048)
			(layers "F.Cu" "F.Mask" "F.Paste")
			(net "FM_PCH_XTAL_INPUT_MODE_MGPIO_TE")
		)
		(pad "H5" smd circle
			(at -8.654796 -7.503668 180)
			(size 0.3048 0.3048)
			(layers "F.Cu" "F.Mask" "F.Paste")
			(net "GND")
		)
		(pad "H8" smd circle
			(at -6.919722 -7.5184 180)
			(size 0.381 0.381)
			(layers "F.Cu" "F.Mask" "F.Paste")
			(net "GND")
		)
		(pad "H11" smd circle
			(at -5.291582 -7.5184 180)
			(size 0.381 0.381)
			(layers "F.Cu" "F.Mask" "F.Paste")
			(net "FM_PCH_TRIGGER0_R_N")
		)
		(pad "H15" smd circle
			(at -3.663188 -7.5184 180)
			(size 0.381 0.381)
			(layers "F.Cu" "F.Mask" "F.Paste")
			(net "TP_CLK_100M_PCH_11_DP")
		)
		(pad "H18" smd circle
			(at -2.035302 -7.5184 180)
			(size 0.381 0.381)
			(layers "F.Cu" "F.Mask" "F.Paste")
			(net "TP_CLK_100M_PCH_8_DP")
		)
		(pad "H21" smd circle
			(at -0.406908 -7.5184 180)
			(size 0.381 0.381)
			(layers "F.Cu" "F.Mask" "F.Paste")
			(net "CLK_100M_PE_M2_0_R_DN")
		)
		(pad "H24" smd circle
			(at 1.220978 -7.5184 180)
			(size 0.381 0.381)
			(layers "F.Cu" "F.Mask" "F.Paste")
			(net "TP_PCH_RSVD<18>")
		)
		(pad "H28" smd circle
			(at 2.849118 -7.5184 180)
			(size 0.381 0.381)
			(layers "F.Cu" "F.Mask" "F.Paste")
			(net "DMI_CPU0_PCH_RX_DP<0>")
		)
		(pad "H31" smd circle
			(at 4.477512 -7.5184 180)
			(size 0.381 0.381)
			(layers "F.Cu" "F.Mask" "F.Paste")
			(net "DMI_CPU0_PCH_RX_DP<2>")
		)
		(pad "H34" smd circle
			(at 6.105398 -7.5184 180)
			(size 0.381 0.381)
			(layers "F.Cu" "F.Mask" "F.Paste")
			(net "DMI_CPU0_PCH_RX_DP<5>")
		)
		(pad "H37" smd circle
			(at 7.733792 -7.5184 180)
			(size 0.381 0.381)
			(layers "F.Cu" "F.Mask" "F.Paste")
			(net "DMI_CPU0_PCH_RX_DP<7>")
		)
		(pad "H39" smd circle
			(at 8.654796 -7.503668 180)
			(size 0.3048 0.3048)
			(layers "F.Cu" "F.Mask" "F.Paste")
			(net "GND")
		)
		(pad "H41" smd circle
			(at 9.484868 -7.503668 180)
			(size 0.3048 0.3048)
			(layers "F.Cu" "F.Mask" "F.Paste")
			(net "TP_P3E_PCH_14_RX_DN")
		)
		(pad "H43" smd oval
			(at 10.31494 -7.503668 270)
			(size 0.254 0.3302)
			(layers "F.Cu" "F.Mask" "F.Paste")
			(net "TP_P3E_PCH_14_RX_DP")
		)
		(pad "J2" smd circle
			(at -9.899904 -7.003288 180)
			(size 0.3048 0.3048)
			(layers "F.Cu" "F.Mask" "F.Paste")
			(net "TP_PCH_MGPIO_TEST1")
		)
		(pad "J4" smd circle
			(at -9.069832 -7.003288 180)
			(size 0.3048 0.3048)
			(layers "F.Cu" "F.Mask" "F.Paste")
			(net "PU_PCH_PMCALERT_N")
		)
		(pad "J7" smd circle
			(at -7.733792 -7.0485 180)
			(size 0.381 0.381)
			(layers "F.Cu" "F.Mask" "F.Paste")
			(net "H_CPU_ERR0_PCH_R_N")
		)
		(pad "J10" smd circle
			(at -6.105398 -7.0485 180)
			(size 0.381 0.381)
			(layers "F.Cu" "F.Mask" "F.Paste")
			(net "PECI_PCH")
		)
		(pad "J13" smd circle
			(at -4.477512 -7.0485 180)
			(size 0.381 0.381)
			(layers "F.Cu" "F.Mask" "F.Paste")
			(net "GND")
		)
		(pad "J16" smd circle
			(at -2.849118 -7.0485 180)
			(size 0.381 0.381)
			(layers "F.Cu" "F.Mask" "F.Paste")
			(net "TP_CLK_100M_PCH_10_DN")
		)
		(pad "J20" smd circle
			(at -1.220978 -7.0485 180)
			(size 0.381 0.381)
			(layers "F.Cu" "F.Mask" "F.Paste")
			(net "GND")
		)
		(pad "J23" smd circle
			(at 0.406908 -7.0485 180)
			(size 0.381 0.381)
			(layers "F.Cu" "F.Mask" "F.Paste")
			(net "TP_PCH_RSVD<19>")
		)
		(pad "J26" smd circle
			(at 2.035302 -7.0485 180)
			(size 0.381 0.381)
			(layers "F.Cu" "F.Mask" "F.Paste")
			(net "GND")
		)
		(pad "J29" smd circle
			(at 3.663188 -7.0485 180)
			(size 0.381 0.381)
			(layers "F.Cu" "F.Mask" "F.Paste")
			(net "DMI_CPU0_PCH_RX_DN<2>")
		)
		(pad "J32" smd circle
			(at 5.291582 -7.0485 180)
			(size 0.381 0.381)
			(layers "F.Cu" "F.Mask" "F.Paste")
			(net "DMI_CPU0_PCH_RX_DN<4>")
		)
		(pad "J36" smd circle
			(at 6.919722 -7.0485 180)
			(size 0.381 0.381)
			(layers "F.Cu" "F.Mask" "F.Paste")
			(net "DMI_CPU0_PCH_RX_DP<6>")
		)
		(pad "J40" smd circle
			(at 9.069832 -7.003288 180)
			(size 0.3048 0.3048)
			(layers "F.Cu" "F.Mask" "F.Paste")
			(net "TP_P3E_PCH_13_RX_DN")
		)
		(pad "J42" smd circle
			(at 9.899904 -7.003288 180)
			(size 0.3048 0.3048)
			(layers "F.Cu" "F.Mask" "F.Paste")
			(net "TP_P3E_PCH_13_RX_DP")
		)
		(pad "K1" smd oval
			(at -10.31494 -6.503162 270)
			(size 0.254 0.3302)
			(layers "F.Cu" "F.Mask" "F.Paste")
			(net "FM_PCH_IO_EXPANDER")
		)
		(pad "K3" smd circle
			(at -9.484868 -6.503162 180)
			(size 0.3048 0.3048)
			(layers "F.Cu" "F.Mask" "F.Paste")
			(net "FM_PCH_MCRO_LDO")
		)
		(pad "K5" smd circle
			(at -8.654796 -6.503162 180)
			(size 0.3048 0.3048)
			(layers "F.Cu" "F.Mask" "F.Paste")
			(net "GND")
		)
		(pad "K8" smd circle
			(at -6.919722 -6.5786 180)
			(size 0.381 0.381)
			(layers "F.Cu" "F.Mask" "F.Paste")
			(net "FM_PCH_TRIGGER1_R_N")
		)
		(pad "K11" smd circle
			(at -5.291582 -6.5786 180)
			(size 0.381 0.381)
			(layers "F.Cu" "F.Mask" "F.Paste")
			(net "GND")
		)
		(pad "K15" smd circle
			(at -3.663188 -6.5786 180)
			(size 0.381 0.381)
			(layers "F.Cu" "F.Mask" "F.Paste")
			(net "GND")
		)
		(pad "K18" smd circle
			(at -2.035302 -6.5786 180)
			(size 0.381 0.381)
			(layers "F.Cu" "F.Mask" "F.Paste")
			(net "TP_CLK_100M_PCH_10_DP")
		)
		(pad "K21" smd circle
			(at -0.406908 -6.5786 180)
			(size 0.381 0.381)
			(layers "F.Cu" "F.Mask" "F.Paste")
			(net "CLK_100M_PE_M2_0_R_DP")
		)
		(pad "K24" smd circle
			(at 1.220978 -6.5786 180)
			(size 0.381 0.381)
			(layers "F.Cu" "F.Mask" "F.Paste")
			(net "GND")
		)
		(pad "K28" smd circle
			(at 2.849118 -6.5786 180)
			(size 0.381 0.381)
			(layers "F.Cu" "F.Mask" "F.Paste")
			(net "DMI_CPU0_PCH_RX_DN<0>")
		)
		(pad "K31" smd circle
			(at 4.477512 -6.5786 180)
			(size 0.381 0.381)
			(layers "F.Cu" "F.Mask" "F.Paste")
			(net "DMI_CPU0_PCH_RX_DP<3>")
		)
		(pad "K34" smd circle
			(at 6.105398 -6.5786 180)
			(size 0.381 0.381)
			(layers "F.Cu" "F.Mask" "F.Paste")
			(net "GND")
		)
		(pad "K37" smd circle
			(at 7.733792 -6.5786 180)
			(size 0.381 0.381)
			(layers "F.Cu" "F.Mask" "F.Paste")
			(net "DMI_CPU0_PCH_RX_DN<6>")
		)
		(pad "K39" smd circle
			(at 8.654796 -6.503162 180)
			(size 0.3048 0.3048)
			(layers "F.Cu" "F.Mask" "F.Paste")
			(net "GND")
		)
		(pad "K41" smd circle
			(at 9.484868 -6.503162 180)
			(size 0.3048 0.3048)
			(layers "F.Cu" "F.Mask" "F.Paste")
			(net "TP_P3E_PCH_12_RX_DN")
		)
		(pad "K43" smd oval
			(at 10.31494 -6.503162 270)
			(size 0.254 0.3302)
			(layers "F.Cu" "F.Mask" "F.Paste")
			(net "TP_P3E_PCH_12_RX_DP")
		)
		(pad "L2" smd circle
			(at -9.899904 -6.002782 180)
			(size 0.3048 0.3048)
			(layers "F.Cu" "F.Mask" "F.Paste")
			(net "FM_PCH_EXTERNALCLKMODE")
		)
		(pad "L4" smd circle
			(at -9.069832 -6.002782 180)
			(size 0.3048 0.3048)
			(layers "F.Cu" "F.Mask" "F.Paste")
			(net "FM_LT_KEY_DOWNGRADE_N")
		)
		(pad "L7" smd circle
			(at -7.733792 -6.1087 180)
			(size 0.381 0.381)
			(layers "F.Cu" "F.Mask" "F.Paste")
			(net "H_CPU_ERR2_PCH_R_N")
		)
		(pad "L10" smd circle
			(at -6.105398 -6.1087 180)
			(size 0.381 0.381)
			(layers "F.Cu" "F.Mask" "F.Paste")
			(net "GND")
		)
		(pad "L13" smd circle
			(at -4.477512 -6.1087 180)
			(size 0.381 0.381)
			(layers "F.Cu" "F.Mask" "F.Paste")
			(net "TP_PCH_RSVD<13>")
		)
		(pad "L16" smd circle
			(at -2.849118 -6.1087 180)
			(size 0.381 0.381)
			(layers "F.Cu" "F.Mask" "F.Paste")
			(net "GND")
		)
		(pad "L20" smd circle
			(at -1.220978 -6.1087 180)
			(size 0.381 0.381)
			(layers "F.Cu" "F.Mask" "F.Paste")
			(net "GND")
		)
		(pad "L23" smd circle
			(at 0.406908 -6.1087 180)
			(size 0.381 0.381)
			(layers "F.Cu" "F.Mask" "F.Paste")
			(net "GND")
		)
		(pad "L26" smd circle
			(at 2.035302 -6.1087 180)
			(size 0.381 0.381)
			(layers "F.Cu" "F.Mask" "F.Paste")
			(net "GND")
		)
		(pad "L29" smd circle
			(at 3.663188 -6.1087 180)
			(size 0.381 0.381)
			(layers "F.Cu" "F.Mask" "F.Paste")
			(net "GND")
		)
		(pad "L32" smd circle
			(at 5.291582 -6.1087 180)
			(size 0.381 0.381)
			(layers "F.Cu" "F.Mask" "F.Paste")
			(net "DMI_CPU0_PCH_RX_DN<3>")
		)
		(pad "L36" smd circle
			(at 6.919722 -6.1087 180)
			(size 0.381 0.381)
			(layers "F.Cu" "F.Mask" "F.Paste")
			(net "GND")
		)
		(pad "L40" smd circle
			(at 9.069832 -6.002782 180)
			(size 0.3048 0.3048)
			(layers "F.Cu" "F.Mask" "F.Paste")
			(net "P3E_PCH_NVS_RX_DN<1>")
		)
		(pad "L42" smd circle
			(at 9.899904 -6.002782 180)
			(size 0.3048 0.3048)
			(layers "F.Cu" "F.Mask" "F.Paste")
			(net "P3E_PCH_NVS_RX_DP<1>")
		)
		(pad "M1" smd oval
			(at -10.31494 -5.502656 270)
			(size 0.254 0.3302)
			(layers "F.Cu" "F.Mask" "F.Paste")
			(net "GND")
		)
		(pad "M3" smd circle
			(at -9.484868 -5.502656 180)
			(size 0.3048 0.3048)
			(layers "F.Cu" "F.Mask" "F.Paste")
			(net "GND")
		)
		(pad "M5" smd circle
			(at -8.654796 -5.502656 180)
			(size 0.3048 0.3048)
			(layers "F.Cu" "F.Mask" "F.Paste")
			(net "GND")
		)
		(pad "M8" smd circle
			(at -6.919722 -5.6388 180)
			(size 0.381 0.381)
			(layers "F.Cu" "F.Mask" "F.Paste")
			(net "TP_PLTRST_N")
		)
		(pad "M11" smd circle
			(at -5.291582 -5.6388 180)
			(size 0.381 0.381)
			(layers "F.Cu" "F.Mask" "F.Paste")
			(net "GND")
		)
		(pad "M15" smd circle
			(at -3.663188 -5.6388 180)
			(size 0.381 0.381)
			(layers "F.Cu" "F.Mask" "F.Paste")
			(net "GND")
		)
		(pad "M18" smd circle
			(at -2.035302 -5.6388 180)
			(size 0.381 0.381)
			(layers "F.Cu" "F.Mask" "F.Paste")
			(net "GND")
		)
		(pad "M21" smd circle
			(at -0.406908 -5.6388 180)
			(size 0.381 0.381)
			(layers "F.Cu" "F.Mask" "F.Paste")
			(net "GND")
		)
		(pad "M24" smd circle
			(at 1.220978 -5.6388 180)
			(size 0.381 0.381)
			(layers "F.Cu" "F.Mask" "F.Paste")
			(net "P1V05_PCH_AUX")
		)
		(pad "M28" smd circle
			(at 2.849118 -5.6388 180)
			(size 0.381 0.381)
			(layers "F.Cu" "F.Mask" "F.Paste")
			(net "GND")
		)
		(pad "M31" smd circle
			(at 4.477512 -5.6388 180)
			(size 0.381 0.381)
			(layers "F.Cu" "F.Mask" "F.Paste")
			(net "GND")
		)
		(pad "M34" smd circle
			(at 6.105398 -5.6388 180)
			(size 0.381 0.381)
			(layers "F.Cu" "F.Mask" "F.Paste")
			(net "GND")
		)
		(pad "M37" smd circle
			(at 7.733792 -5.6388 180)
			(size 0.381 0.381)
			(layers "F.Cu" "F.Mask" "F.Paste")
			(net "GND")
		)
		(pad "M39" smd circle
			(at 8.654796 -5.502656 180)
			(size 0.3048 0.3048)
			(layers "F.Cu" "F.Mask" "F.Paste")
			(net "GND")
		)
		(pad "M41" smd circle
			(at 9.484868 -5.502656 180)
			(size 0.3048 0.3048)
			(layers "F.Cu" "F.Mask" "F.Paste")
			(net "P3E_PCH_NVS_RX_DN<0>")
		)
		(pad "M43" smd oval
			(at 10.31494 -5.502656 270)
			(size 0.254 0.3302)
			(layers "F.Cu" "F.Mask" "F.Paste")
			(net "P3E_PCH_NVS_RX_DP<0>")
		)
		(pad "N2" smd circle
			(at -9.899904 -5.002276 180)
			(size 0.3048 0.3048)
			(layers "F.Cu" "F.Mask" "F.Paste")
			(net "PD_GPP_I_13")
		)
		(pad "N4" smd circle
			(at -9.069832 -5.002276 180)
			(size 0.3048 0.3048)
			(layers "F.Cu" "F.Mask" "F.Paste")
			(net "IRQ_TPM_SPI_N")
		)
		(pad "N7" smd circle
			(at -7.733792 -5.1689 180)
			(size 0.381 0.381)
			(layers "F.Cu" "F.Mask" "F.Paste")
			(net "FAB_REV_ID0")
		)
		(pad "N10" smd circle
			(at -6.105398 -5.1689 180)
			(size 0.381 0.381)
			(layers "F.Cu" "F.Mask" "F.Paste")
			(net "PD_GPP_M_16")
		)
		(pad "N13" smd circle
			(at -4.477512 -5.1689 180)
			(size 0.381 0.381)
			(layers "F.Cu" "F.Mask" "F.Paste")
			(net "TP_PCH_RSVD<12>")
		)
		(pad "N16" smd circle
			(at -2.849118 -5.1689 180)
			(size 0.381 0.381)
			(layers "F.Cu" "F.Mask" "F.Paste")
			(net "GND")
		)
		(pad "N20" smd circle
			(at -1.220978 -5.1689 180)
			(size 0.381 0.381)
			(layers "F.Cu" "F.Mask" "F.Paste")
			(net "P1V8_PCH_AUX")
		)
		(pad "N23" smd circle
			(at 0.406908 -5.1689 180)
			(size 0.381 0.381)
			(layers "F.Cu" "F.Mask" "F.Paste")
			(net "P1V05_PCH_AUX")
		)
		(pad "N26" smd circle
			(at 2.035302 -5.1689 180)
			(size 0.381 0.381)
			(layers "F.Cu" "F.Mask" "F.Paste")
			(net "P1V05_PCH_AUX")
		)
		(pad "N29" smd circle
			(at 3.663188 -5.1689 180)
			(size 0.381 0.381)
			(layers "F.Cu" "F.Mask" "F.Paste")
			(net "PD_PCH_XCLK_BIASREF")
		)
		(pad "N32" smd circle
			(at 5.291582 -5.1689 180)
			(size 0.381 0.381)
			(layers "F.Cu" "F.Mask" "F.Paste")
			(net "GND")
		)
		(pad "N36" smd circle
			(at 6.919722 -5.1689 180)
			(size 0.381 0.381)
			(layers "F.Cu" "F.Mask" "F.Paste")
			(net "TP_P3E_PCH_15_TX_DP")
		)
		(pad "N40" smd circle
			(at 9.069832 -5.002276 180)
			(size 0.3048 0.3048)
			(layers "F.Cu" "F.Mask" "F.Paste")
			(net "NC_PCH_RSVD<10>")
		)
		(pad "N42" smd circle
			(at 9.899904 -5.002276 180)
			(size 0.3048 0.3048)
			(layers "F.Cu" "F.Mask" "F.Paste")
			(net "NC_PCH_RSVD<11>")
		)
		(pad "P1" smd oval
			(at -10.31494 -4.50215 270)
			(size 0.254 0.3302)
			(layers "F.Cu" "F.Mask" "F.Paste")
			(net "PD_GPP_I_14")
		)
		(pad "P3" smd circle
			(at -9.484868 -4.50215 180)
			(size 0.3048 0.3048)
			(layers "F.Cu" "F.Mask" "F.Paste")
			(net "FM_PCH_DFXTESTMODE")
		)
		(pad "P5" smd circle
			(at -8.654796 -4.50215 180)
			(size 0.3048 0.3048)
			(layers "F.Cu" "F.Mask" "F.Paste")
			(net "GND")
		)
		(pad "P8" smd circle
			(at -6.919722 -4.699 180)
			(size 0.381 0.381)
			(layers "F.Cu" "F.Mask" "F.Paste")
			(net "GND")
		)
		(pad "P11" smd circle
			(at -5.291582 -4.699 180)
			(size 0.381 0.381)
			(layers "F.Cu" "F.Mask" "F.Paste")
			(net "GND")
		)
		(pad "P15" smd circle
			(at -3.663188 -4.699 180)
			(size 0.381 0.381)
			(layers "F.Cu" "F.Mask" "F.Paste")
			(net "P1V05_PCH_AUX")
		)
		(pad "P18" smd circle
			(at -2.035302 -4.699 180)
			(size 0.381 0.381)
			(layers "F.Cu" "F.Mask" "F.Paste")
			(net "TP_PCH_RSVD<6>")
		)
		(pad "P21" smd circle
			(at -0.406908 -4.699 180)
			(size 0.381 0.381)
			(layers "F.Cu" "F.Mask" "F.Paste")
			(net "P3V3_AUX")
		)
		(pad "P24" smd circle
			(at 1.220978 -4.699 180)
			(size 0.381 0.381)
			(layers "F.Cu" "F.Mask" "F.Paste")
			(net "GND")
		)
		(pad "P28" smd circle
			(at 2.849118 -4.699 180)
			(size 0.381 0.381)
			(layers "F.Cu" "F.Mask" "F.Paste")
			(net "GND")
		)
		(pad "P31" smd circle
			(at 4.477512 -4.699 180)
			(size 0.381 0.381)
			(layers "F.Cu" "F.Mask" "F.Paste")
			(net "GND")
		)
		(pad "P34" smd circle
			(at 6.105398 -4.699 180)
			(size 0.381 0.381)
			(layers "F.Cu" "F.Mask" "F.Paste")
			(net "TP_P3E_PCH_15_TX_DN")
		)
		(pad "P37" smd circle
			(at 7.733792 -4.699 180)
			(size 0.381 0.381)
			(layers "F.Cu" "F.Mask" "F.Paste")
			(net "GND")
		)
		(pad "P39" smd circle
			(at 8.654796 -4.50215 180)
			(size 0.3048 0.3048)
			(layers "F.Cu" "F.Mask" "F.Paste")
			(net "GND")
		)
		(pad "P41" smd circle
			(at 9.484868 -4.50215 180)
			(size 0.3048 0.3048)
			(layers "F.Cu" "F.Mask" "F.Paste")
			(net "GND")
		)
		(pad "P43" smd oval
			(at 10.31494 -4.50215 270)
			(size 0.254 0.3302)
			(layers "F.Cu" "F.Mask" "F.Paste")
			(net "GND")
		)
		(pad "R2" smd circle
			(at -9.899904 -4.002024 180)
			(size 0.3048 0.3048)
			(layers "F.Cu" "F.Mask" "F.Paste")
			(net "PD_GPP_I_15")
		)
		(pad "R4" smd circle
			(at -9.069832 -4.002024 180)
			(size 0.3048 0.3048)
			(layers "F.Cu" "F.Mask" "F.Paste")
			(net "FM_PCH_XTALSEL")
		)
	)
)
